(kicad_pcb
	(version 20221018)
	(generator pcbnew)
	(general
    (thickness 1.562)
  )
	(paper "A4")
	(title_block
    (title "Thunderbolt PCIe Adaper")
    (date "2024-07-09")
    (rev "1.0.3")
    (comment 1 "www.antmicro.com")
    (comment 2 "Antmicro Ltd.")
		(comment 9 "footprints 26-33 of 271")
	)
	(layers
    (0 "F.Cu" signal)
    (1 "In1.Cu" signal)
    (2 "In2.Cu" signal)
    (3 "In3.Cu" signal)
    (4 "In4.Cu" signal)
    (31 "B.Cu" signal)
    (32 "B.Adhes" user "B.Adhesive")
    (33 "F.Adhes" user "F.Adhesive")
    (34 "B.Paste" user)
    (35 "F.Paste" user)
    (36 "B.SilkS" user "B.Silkscreen")
    (37 "F.SilkS" user "F.Silkscreen")
    (38 "B.Mask" user)
    (39 "F.Mask" user)
    (40 "Dwgs.User" user "User.Drawings")
    (41 "Cmts.User" user "User.Comments")
    (42 "Eco1.User" user "User.Eco1")
    (43 "Eco2.User" user "User.Eco2")
    (44 "Edge.Cuts" user)
    (45 "Margin" user)
    (46 "B.CrtYd" user "B.Courtyard")
    (47 "F.CrtYd" user "F.Courtyard")
    (48 "B.Fab" user)
    (49 "F.Fab" user)
  )
	(footprint "antmicro-footprints:LED_0603_1608Metric_G" (layer "F.Cu")
    (at 106.9455 89.2)
    (descr "LED SMD 0603 Green")
    (tags "LED SMD 0603 Green")
    (property "Author" "Antmicro")
    (property "Color" "Green")
    (property "License" "Apache-2.0")
    (property "MPN" "KP-1608CGCK")
    (property "Manufacturer" "Kingbright")
    (property "Sheetfile" "power.kicad_sch")
    (property "Sheetname" "Power")
    (property "ki_description" "LED, Green, SMD, 0603, 20 mA, 2.1 V, 570 nm")
    (property "ki_keywords" "SMT, DIODE, SEMICONDUCTOR, LED")
    (attr smd)
    (fp_text reference "D5" (at -2.6785 0.462) (layer "F.SilkS")
        (effects (font (size 0.7 0.7) (thickness 0.15)) (justify left bottom))
    )
    (fp_text value "LED_G_0603_KP-1608CGCK" (at -0.001 1.599) (layer "F.Fab")
        (effects (font (size 0.7 0.7) (thickness 0.15)) (justify left bottom))
    )
    (fp_text user "License: Apache-2.0" (at -1.4224 3.599) (layer "F.Fab") hide
        (effects (font (size 0.7 0.7) (thickness 0.15)) (justify left bottom))
    )
    (fp_text user "Author: Antmicro" (at -1.4224 4.799) (layer "F.Fab") hide
        (effects (font (size 0.7 0.7) (thickness 0.15)) (justify left bottom))
    )
    (fp_text user "${REFERENCE}" (at -1.4224 5.999) (layer "F.Fab") hide
        (effects (font (size 0.7 0.7) (thickness 0.15)) (justify left bottom))
    )
    (fp_line (start -1.18 -0.319) (end -1.18 0.321)
      (stroke (width 0.15) (type solid)) (layer "F.SilkS"))
    (fp_line (start -0.094672 0.001008) (end -0.24 0.001008)
      (stroke (width 0.1) (type solid)) (layer "F.SilkS"))
    (fp_line (start -0.094672 0.001008) (end 0.105328 -0.198992)
      (stroke (width 0.1) (type solid)) (layer "F.SilkS"))
    (fp_line (start -0.094672 0.201008) (end -0.094672 -0.198992)
      (stroke (width 0.1) (type solid)) (layer "F.SilkS"))
    (fp_line (start 0.105328 0.001008) (end 0.24 0.001)
      (stroke (width 0.1) (type solid)) (layer "F.SilkS"))
    (fp_line (start 0.105328 0.201008) (end -0.094672 0.001008)
      (stroke (width 0.1) (type solid)) (layer "F.SilkS"))
    (fp_line (start 0.105328 0.201008) (end 0.105328 -0.198992)
      (stroke (width 0.1) (type solid)) (layer "F.SilkS"))
    (fp_line (start 0.22 -0.35) (end -0.22 -0.35)
      (stroke (width 0.15) (type solid)) (layer "F.SilkS"))
    (fp_line (start 0.22 0.35) (end -0.22 0.35)
      (stroke (width 0.15) (type solid)) (layer "F.SilkS"))
    (fp_rect (start 1.25 0.65) (end -1.25 -0.65)
      (stroke (width 0.05) (type solid)) (fill none) (layer "F.CrtYd"))
    (fp_line (start -0.199 -0.202) (end -0.199 0.1)
      (stroke (width 0.15) (type solid)) (layer "F.Fab"))
    (fp_line (start -0.199 0) (end -0.597 0)
      (stroke (width 0.15) (type solid)) (layer "F.Fab"))
    (fp_line (start -0.199 0.2) (end -0.199 0.1)
      (stroke (width 0.15) (type solid)) (layer "F.Fab"))
    (fp_line (start -0.101 0) (end 0.201 0.2)
      (stroke (width 0.15) (type solid)) (layer "F.Fab"))
    (fp_line (start 0.201 -0.202) (end -0.101 0)
      (stroke (width 0.15) (type solid)) (layer "F.Fab"))
    (fp_line (start 0.201 0) (end 0.201 -0.202)
      (stroke (width 0.15) (type solid)) (layer "F.Fab"))
    (fp_line (start 0.201 0.2) (end 0.201 0)
      (stroke (width 0.15) (type solid)) (layer "F.Fab"))
    (fp_line (start 0.599 0) (end 0.201 0)
      (stroke (width 0.15) (type solid)) (layer "F.Fab"))
    (fp_rect (start 0.848 0.4) (end -0.85 -0.402)
      (stroke (width 0.15) (type solid)) (fill none) (layer "F.Fab"))
    (pad "1" smd roundrect (at -0.7 0 180) (size 0.8 1) (layers "F.Cu" "F.Paste" "F.Mask") (roundrect_rratio 0.2)
      (net 123 "Net-(D5-C)") (pinfunction "C") (pintype "passive"))
    (pad "2" smd roundrect (at 0.7 0 180) (size 0.8 1) (layers "F.Cu" "F.Paste" "F.Mask") (roundrect_rratio 0.2)
      (net 61 "12V0_MOLEX") (pinfunction "A") (pintype "passive"))
  )
	(footprint "antmicro-footprints:C_0805_2012Metric" (layer "F.Cu")
    (at 105.01 74.11 90)
    (descr "Capacitor SMD 0805")
    (tags "capacitor SMD 0805")
    (property "Author" "Antmicro")
    (property "Dielectric" "")
    (property "License" "Apache-2.0")
    (property "MPN" "GRM21BR6YA106KE43L")
    (property "Manufacturer" "Murata")
    (property "Sheetfile" "power.kicad_sch")
    (property "Sheetname" "Power")
    (property "Val" "10u")
    (property "Voltage" "35V")
    (property "ki_description" "SMD Multilayer Ceramic Capacitor, 10 µF, 35 V, 0805 [2012 Metric], ± 10%, X5R, GRM Series")
    (property "ki_keywords" "0805, SMT, CAPACITOR, PASSIVE")
    (attr smd)
    (fp_text reference "C7" (at 1.974 0.4 90) (layer "F.SilkS")
        (effects (font (size 0.7 0.7) (thickness 0.15)) (justify left bottom))
    )
    (fp_text value "C_10u_0805_35V" (at -2.055717 1.963152 90) (layer "F.Fab")
        (effects (font (size 0.7 0.7) (thickness 0.15)) (justify left bottom))
    )
    (fp_text user "${REFERENCE}" (at -1.9 3.947 90) (layer "F.Fab") hide
        (effects (font (size 0.7 0.7) (thickness 0.15)) (justify left bottom))
    )
    (fp_text user "License: Apache-2.0" (at -1.9 4.947 90) (layer "F.Fab") hide
        (effects (font (size 0.7 0.7) (thickness 0.15)) (justify left bottom))
    )
    (fp_text user "Author: Antmicro" (at -1.9 5.947 90) (layer "F.Fab") hide
        (effects (font (size 0.7 0.7) (thickness 0.15)) (justify left bottom))
    )
    (fp_line (start -0.3 -0.7) (end 0.3 -0.7)
      (stroke (width 0.15) (type solid)) (layer "F.SilkS"))
    (fp_line (start -0.3 0.7) (end 0.3 0.7)
      (stroke (width 0.15) (type solid)) (layer "F.SilkS"))
    (fp_rect (start 1.95 -0.9) (end -1.95 0.9)
      (stroke (width 0.05) (type default)) (fill none) (layer "F.CrtYd"))
    (fp_rect (start -0.95 -0.675) (end 0.95 0.675)
      (stroke (width 0.15) (type solid)) (fill none) (layer "F.Fab"))
    (pad "1" smd roundrect (at -1.1 0 90) (size 1.2 1.3) (layers "F.Cu" "F.Paste" "F.Mask") (roundrect_rratio 0.25)
      (net 1 "GND") (pintype "passive"))
    (pad "2" smd roundrect (at 1.1 0 90) (size 1.2 1.3) (layers "F.Cu" "F.Paste" "F.Mask") (roundrect_rratio 0.25)
      (net 3 "5V0_USB") (pintype "passive"))
  )
	(footprint "antmicro-footprints:C_0603_1608Metric" (layer "F.Cu")
    (at 144.4 72.3 90)
    (descr "Capacitor SMD 0603")
    (tags "capacitor 0603")
    (property "Author" "Antmicro")
    (property "Dielectric" "")
    (property "License" "Apache-2.0")
    (property "MPN" "GRM188R60J226MEA0D")
    (property "Manufacturer" "Murata")
    (property "Sheetfile" "tb-power.kicad_sch")
    (property "Sheetname" "Thunderbolt Controller - Power")
    (property "Val" "22u")
    (property "Voltage" "")
    (property "ki_description" "SMD Multilayer Ceramic Capacitor, 22 µF, 6.3 V, 0603 [1608 Metric], ± 20%, X5R, GRM Series")
    (property "ki_keywords" "0603, SMT, CAPACITOR, PASSIVE, CERAMIC, MLCC")
    (attr smd)
    (fp_text reference "C79" (at -3.519 0.483 90) (layer "F.SilkS")
        (effects (font (size 0.7 0.7) (thickness 0.15)) (justify left bottom))
    )
    (fp_text value "C_22u_0603" (at -1.42757 1.770288 90) (layer "F.Fab")
        (effects (font (size 0.7 0.7) (thickness 0.15)) (justify left bottom))
    )
    (fp_text user "Author: Antmicro" (at -1.682 4.894 90) (layer "F.Fab") hide
        (effects (font (size 0.7 0.7) (thickness 0.15)) (justify left bottom))
    )
    (fp_text user "${REFERENCE}" (at -1.682 3.895 90) (layer "F.Fab") hide
        (effects (font (size 0.7 0.7) (thickness 0.15)) (justify left bottom))
    )
    (fp_text user "License: Apache-2.0" (at -1.682 5.895 90) (layer "F.Fab") hide
        (effects (font (size 0.7 0.7) (thickness 0.15)) (justify left bottom))
    )
    (fp_line (start -0.15 -0.4) (end 0.15 -0.4)
      (stroke (width 0.15) (type solid)) (layer "F.SilkS"))
    (fp_line (start -0.15 0.4) (end 0.15 0.4)
      (stroke (width 0.15) (type solid)) (layer "F.SilkS"))
    (fp_rect (start -1.25 -0.65) (end 1.25 0.65)
      (stroke (width 0.05) (type solid)) (fill none) (layer "F.CrtYd"))
    (fp_rect (start -0.8 -0.4) (end 0.8 0.4)
      (stroke (width 0.15) (type solid)) (fill none) (layer "F.Fab"))
    (pad "1" smd roundrect (at -0.7 0 90) (size 0.8 1) (layers "F.Cu" "F.Paste" "F.Mask") (roundrect_rratio 0.2)
      (net 1 "GND") (pintype "passive"))
    (pad "2" smd roundrect (at 0.7 0 90) (size 0.8 1) (layers "F.Cu" "F.Paste" "F.Mask") (roundrect_rratio 0.2)
      (net 112 "Net-(U4A-VCC0P9_SVR_SENSE)") (pintype "passive"))
  )
	(footprint "antmicro-footprints:L_Coilcraft-XAL5030" (layer "F.Cu")
    (at 121.6 64.455 90)
    (property "Author" "Antmicro")
    (property "IMax" "9.7 A")
    (property "ISat" "9.2 A")
    (property "License" "Apache-2.0")
    (property "MPN" "XAL5030-222MEC")
    (property "Manufacturer" "Coilcraft")
    (property "Sheetfile" "power.kicad_sch")
    (property "Sheetname" "Power")
    (property "Size" "5.28x5.48")
    (property "Val" "2u2/9.7A")
    (property "ki_description" "Power Inductor (SMT), 2.2 µH, 9.7 A, Shielded, 9.2 A, XAL5030")
    (property "ki_keywords" "SMT, INDUCTOR, PASSIVE")
    (attr smd)
    (fp_text reference "L2" (at 2.987 -0.823 180) (layer "F.SilkS")
        (effects (font (size 0.7 0.7) (thickness 0.15)) (justify left bottom))
    )
    (fp_text value "L_2u2_9.7A_Coilcraft-XAL5030" (at 0 4.241 90) (layer "F.Fab")
        (effects (font (size 0.7 0.7) (thickness 0.15)) (justify left bottom))
    )
    (fp_text user "License: Apache-2.0" (at -2.89 6.241 90) (layer "F.Fab") hide
        (effects (font (size 0.7 0.7) (thickness 0.15)) (justify left bottom))
    )
    (fp_text user "${REFERENCE}" (at -2.89 8.641 90) (layer "F.Fab") hide
        (effects (font (size 0.7 0.7) (thickness 0.15)) (justify left bottom))
    )
    (fp_text user "Author: Antmicro" (at -2.89 7.441 90) (layer "F.Fab") hide
        (effects (font (size 0.7 0.7) (thickness 0.15)) (justify left bottom))
    )
    (fp_line (start -2.74 -2.84) (end 2.74 -2.84)
      (stroke (width 0.15) (type solid)) (layer "F.SilkS"))
    (fp_line (start -2.74 2.84) (end -2.74 -2.84)
      (stroke (width 0.15) (type solid)) (layer "F.SilkS"))
    (fp_line (start -2.74 2.84) (end 2.74 2.84)
      (stroke (width 0.15) (type solid)) (layer "F.SilkS"))
    (fp_line (start 2.74 2.84) (end 2.74 -2.84)
      (stroke (width 0.15) (type solid)) (layer "F.SilkS"))
    (fp_rect (start -2.89 -2.99) (end 2.89 2.99)
      (stroke (width 0.05) (type solid)) (fill none) (layer "F.CrtYd"))
    (fp_line (start -2.74 -2.84) (end 2.74 -2.84)
      (stroke (width 0.15) (type solid)) (layer "F.Fab"))
    (fp_line (start -2.74 2.84) (end -2.74 -2.84)
      (stroke (width 0.15) (type solid)) (layer "F.Fab"))
    (fp_line (start 2.74 -2.84) (end 2.74 2.84)
      (stroke (width 0.15) (type solid)) (layer "F.Fab"))
    (fp_line (start 2.74 2.84) (end -2.74 2.84)
      (stroke (width 0.15) (type solid)) (layer "F.Fab"))
    (pad "1" smd roundrect (at -1.655 0 90) (size 1.18 4.7) (layers "F.Cu" "F.Paste" "F.Mask") (roundrect_rratio 0.1)
      (net 95 "Net-(U2-SW)") (pintype "passive"))
    (pad "2" smd roundrect (at 1.655 0 90) (size 1.18 4.7) (layers "F.Cu" "F.Paste" "F.Mask") (roundrect_rratio 0.1)
      (net 100 "Net-(D2-A)") (pintype "passive"))
  )
	(footprint "antmicro-footprints:C_0603_1608Metric" (layer "F.Cu")
    (at 142.9 69.7 -90)
    (descr "Capacitor SMD 0603")
    (tags "capacitor 0603")
    (property "Author" "Antmicro")
    (property "Dielectric" "")
    (property "License" "Apache-2.0")
    (property "MPN" "GRM188R60J226MEA0D")
    (property "Manufacturer" "Murata")
    (property "Sheetfile" "tb-power.kicad_sch")
    (property "Sheetname" "Thunderbolt Controller - Power")
    (property "Val" "22u")
    (property "Voltage" "")
    (property "ki_description" "SMD Multilayer Ceramic Capacitor, 22 µF, 6.3 V, 0603 [1608 Metric], ± 20%, X5R, GRM Series")
    (property "ki_keywords" "0603, SMT, CAPACITOR, PASSIVE, CERAMIC, MLCC")
    (attr smd)
    (fp_text reference "C86" (at -1.247 -0.483 -90) (layer "F.SilkS")
        (effects (font (size 0.7 0.7) (thickness 0.15)) (justify left bottom))
    )
    (fp_text value "C_22u_0603" (at -1.42757 1.770288 -90) (layer "F.Fab")
        (effects (font (size 0.7 0.7) (thickness 0.15)) (justify left bottom))
    )
    (fp_text user "Author: Antmicro" (at -1.682 4.894 -90) (layer "F.Fab") hide
        (effects (font (size 0.7 0.7) (thickness 0.15)) (justify left bottom))
    )
    (fp_text user "License: Apache-2.0" (at -1.682 5.895 -90) (layer "F.Fab") hide
        (effects (font (size 0.7 0.7) (thickness 0.15)) (justify left bottom))
    )
    (fp_text user "${REFERENCE}" (at -1.682 3.895 -90) (layer "F.Fab") hide
        (effects (font (size 0.7 0.7) (thickness 0.15)) (justify left bottom))
    )
    (fp_line (start -0.15 -0.4) (end 0.15 -0.4)
      (stroke (width 0.15) (type solid)) (layer "F.SilkS"))
    (fp_line (start -0.15 0.4) (end 0.15 0.4)
      (stroke (width 0.15) (type solid)) (layer "F.SilkS"))
    (fp_rect (start -1.25 -0.65) (end 1.25 0.65)
      (stroke (width 0.05) (type solid)) (fill none) (layer "F.CrtYd"))
    (fp_rect (start -0.8 -0.4) (end 0.8 0.4)
      (stroke (width 0.15) (type solid)) (fill none) (layer "F.Fab"))
    (pad "1" smd roundrect (at -0.7 0 270) (size 0.8 1) (layers "F.Cu" "F.Paste" "F.Mask") (roundrect_rratio 0.2)
      (net 1 "GND") (pintype "passive"))
    (pad "2" smd roundrect (at 0.7 0 270) (size 0.8 1) (layers "F.Cu" "F.Paste" "F.Mask") (roundrect_rratio 0.2)
      (net 112 "Net-(U4A-VCC0P9_SVR_SENSE)") (pintype "passive"))
  )
	(footprint "antmicro-footprints:Fiducial_1mm_Mask3mm" (layer "F.Cu")
    (at 108.7 52)
    (descr "Circular Fiducial, 1.5mm bare copper, 3mm soldermask opening")
    (tags "fiducial")
    (property "Author" "Antmicro")
    (property "License" "Apache-2.0")
    (property "Sheetfile" "thunderbolt-pcie-adapter.kicad_sch")
    (property "Sheetname" "")
    (property "exclude_from_bom" "")
    (property "ki_description" "Fiducial mask")
    (attr through_hole exclude_from_bom)
    (fp_text reference "FID2" (at -1.258 2.61) (layer "F.SilkS")
        (effects (font (size 0.7 0.7) (thickness 0.15)) (justify left bottom))
    )
    (fp_text value "Fiducial_1mm_Mask3mm" (at 0 2.603) (layer "F.Fab")
        (effects (font (size 0.7 0.7) (thickness 0.15)) (justify left bottom))
    )
    (fp_text user "License: Apache-2.0" (at -1.25 7.003) (layer "F.Fab") hide
        (effects (font (size 0.7 0.7) (thickness 0.15)) (justify left bottom))
    )
    (fp_text user "Author: Antmicro" (at -1.25 5.803) (layer "F.Fab") hide
        (effects (font (size 0.7 0.7) (thickness 0.15)) (justify left bottom))
    )
    (fp_text user "${REFERENCE}" (at -1.25 4.603) (layer "F.Fab") hide
        (effects (font (size 0.7 0.7) (thickness 0.15)) (justify left bottom))
    )
    (fp_circle (center 0 0) (end 1.5 0)
      (stroke (width 0.05) (type solid)) (fill none) (layer "F.CrtYd"))
    (fp_circle (center 0 0) (end 1.5 0)
      (stroke (width 0.15) (type solid)) (fill none) (layer "F.Fab"))
    (pad "" smd circle (at 0 0) (size 1 1) (layers "F.Cu" "F.Mask")
      (solder_mask_margin 1) (clearance 1))
  )
	(footprint "antmicro-footprints:C_0603_1608Metric" (layer "F.Cu")
    (at 144.4 69.7 -90)
    (descr "Capacitor SMD 0603")
    (tags "capacitor 0603")
    (property "Author" "Antmicro")
    (property "Dielectric" "")
    (property "License" "Apache-2.0")
    (property "MPN" "GRM188R60J226MEA0D")
    (property "Manufacturer" "Murata")
    (property "Sheetfile" "tb-power.kicad_sch")
    (property "Sheetname" "Thunderbolt Controller - Power")
    (property "Val" "22u")
    (property "Voltage" "")
    (property "ki_description" "SMD Multilayer Ceramic Capacitor, 22 µF, 6.3 V, 0603 [1608 Metric], ± 20%, X5R, GRM Series")
    (property "ki_keywords" "0603, SMT, CAPACITOR, PASSIVE, CERAMIC, MLCC")
    (attr smd)
    (fp_text reference "C89" (at -1.247 -0.483 -90) (layer "F.SilkS")
        (effects (font (size 0.7 0.7) (thickness 0.15)) (justify left bottom))
    )
    (fp_text value "C_22u_0603" (at -1.42757 1.770288 -90) (layer "F.Fab")
        (effects (font (size 0.7 0.7) (thickness 0.15)) (justify left bottom))
    )
    (fp_text user "${REFERENCE}" (at -1.682 3.895 -90) (layer "F.Fab") hide
        (effects (font (size 0.7 0.7) (thickness 0.15)) (justify left bottom))
    )
    (fp_text user "Author: Antmicro" (at -1.682 4.894 -90) (layer "F.Fab") hide
        (effects (font (size 0.7 0.7) (thickness 0.15)) (justify left bottom))
    )
    (fp_text user "License: Apache-2.0" (at -1.682 5.895 -90) (layer "F.Fab") hide
        (effects (font (size 0.7 0.7) (thickness 0.15)) (justify left bottom))
    )
    (fp_line (start -0.15 -0.4) (end 0.15 -0.4)
      (stroke (width 0.15) (type solid)) (layer "F.SilkS"))
    (fp_line (start -0.15 0.4) (end 0.15 0.4)
      (stroke (width 0.15) (type solid)) (layer "F.SilkS"))
    (fp_rect (start -1.25 -0.65) (end 1.25 0.65)
      (stroke (width 0.05) (type solid)) (fill none) (layer "F.CrtYd"))
    (fp_rect (start -0.8 -0.4) (end 0.8 0.4)
      (stroke (width 0.15) (type solid)) (fill none) (layer "F.Fab"))
    (pad "1" smd roundrect (at -0.7 0 270) (size 0.8 1) (layers "F.Cu" "F.Paste" "F.Mask") (roundrect_rratio 0.2)
      (net 1 "GND") (pintype "passive"))
    (pad "2" smd roundrect (at 0.7 0 270) (size 0.8 1) (layers "F.Cu" "F.Paste" "F.Mask") (roundrect_rratio 0.2)
      (net 112 "Net-(U4A-VCC0P9_SVR_SENSE)") (pintype "passive"))
  )
	(footprint "antmicro-footprints:TP_SMD_0.75mm" (layer "F.Cu")
    (at 113.7 81.9)
    (property "Author" "Antmicro")
    (property "License" "Apache-2.0")
    (property "MPN" "")
    (property "Manufacturer" "")
    (property "Sheetfile" "power.kicad_sch")
    (property "Sheetname" "Power")
    (property "exclude_from_bom" "")
    (property "ki_description" "SMT test point")
    (property "ki_keywords" "TESTPOINT")
    (attr exclude_from_pos_files exclude_from_bom)
    (fp_text reference "TP4" (at 0.6 0.396) (layer "F.SilkS")
        (effects (font (size 0.7 0.7) (thickness 0.15)) (justify left bottom))
    )
    (fp_text value "TP_0.75mm_SMD" (at 0 1.2) (layer "F.Fab")
        (effects (font (size 0.7 0.7) (thickness 0.15)) (justify left bottom))
    )
    (fp_text user "${REFERENCE}" (at -0.4 2.7) (layer "F.Fab") hide
        (effects (font (size 0.7 0.7) (thickness 0.15)) (justify left bottom))
    )
    (fp_text user "License: Apache-2.0" (at -0.4 5.101) (layer "F.Fab") hide
        (effects (font (size 0.7 0.7) (thickness 0.15)) (justify left bottom))
    )
    (fp_text user "Author: Antmicro" (at -0.4 3.901) (layer "F.Fab") hide
        (effects (font (size 0.7 0.7) (thickness 0.15)) (justify left bottom))
    )
    (fp_circle (center 0 0) (end 0.475 0)
      (stroke (width 0.05) (type default)) (fill none) (layer "F.CrtYd"))
    (pad "1" smd circle (at 0 0) (size 0.75 0.75) (layers "F.Cu" "F.Mask")
      (net 205 "Net-(U1-LOADTG)") (pinfunction "1") (pintype "passive"))
  )
)
